# SCM (Grand Teton) — schematic netlist excerpt (pin names and nets, part order shuffled) for the footprints in the layout excerpt that follows; sources: Cadence DE-HDL packaged netlist, KiCad conversion of 12092022_DA0F0TMDCD0_F0T_Management_Board_D_brd_V3_OCP.brd

R240  Q_RES  4.7K 1% CHIP  pkg 0402LF  page 13 : A = P3V3_AUX ; B = PU_FWSPIWP_N
C270  Q_CAP  1UF 16V 10% EMPTY  pkg 0402  page 17 : A = LPC_ESPI_SEL_N ; B = GND

(kicad_pcb
	(version 20260206)
	(generator "pcbnew")
	(generator_version "10.0")
	(general
		(thickness 1.6)
		(legacy_teardrops no)
	)
	(paper "A4")
	(title_block
		(title "12092022_DA0F0TMDCD0_F0T_Management_Board_D_brd_V3_OCP.brd")
		(comment 1 "Grand Teton / footprints 743-744 of 1440")
	)
	(layers
		(0 "F.Cu" signal "TOP")
		(4 "In1.Cu" signal "GND")
		(6 "In2.Cu" signal "IN1")
		(8 "In3.Cu" signal "GND1")
		(10 "In4.Cu" signal "IN2")
		(12 "In5.Cu" signal "VCC")
		(14 "In6.Cu" signal "VCC1")
		(16 "In7.Cu" signal "IN3")
		(18 "In8.Cu" signal "GND2")
		(20 "In9.Cu" signal "IN4")
		(22 "In10.Cu" signal "GND3")
		(2 "B.Cu" signal "BOTTOM")
		(9 "F.Adhes" user "F.Adhesive")
		(11 "B.Adhes" user "B.Adhesive")
		(13 "F.Paste" user "Package Geometry/Pastemask Top")
		(15 "B.Paste" user "Package Geometry/Pastemask Bottom")
		(5 "F.SilkS" user "Ref Des/Silkscreen Top")
		(7 "B.SilkS" user "Ref Des/Silkscreen Bottom")
		(1 "F.Mask" user "Board Geometry/Soldermask Top")
		(3 "B.Mask" user "Board Geometry/Soldermask Bottom")
		(17 "Dwgs.User" user "User.Drawings")
		(19 "Cmts.User" user "User.Comments")
		(21 "Eco1.User" user "User.Eco1")
		(23 "Eco2.User" user "User.Eco2")
		(25 "Edge.Cuts" user "Board Geometry/Outline")
		(27 "Margin" user)
		(31 "F.CrtYd" user "Package Geometry/Place Bound Top")
		(29 "B.CrtYd" user "Package Geometry/Place Bound Bottom")
		(35 "F.Fab" user "Ref Des/Assembly Top")
		(33 "B.Fab" user "Ref Des/Assembly Bottom")
	)
	(footprint ""
		(layer "B.Cu")
		(at 79.629 -93.726 180)
		(property "Reference" "C270"
			(at 0 0 0)
			(layer "B.SilkS")
			(hide yes)
			(effects
				(font
					(size 1.27 1.27)
				)
				(justify mirror)
			)
		)
		(property "Value" ""
			(at 0 0 0)
			(layer "B.Fab")
			(effects
				(font
					(size 1.27 1.27)
				)
				(justify mirror)
			)
		)
		(duplicate_pad_numbers_are_jumpers no)
		(fp_line
			(start 0.7874 0.4064)
			(end 0.7874 -0.4064)
			(stroke
				(width 0.1524)
				(type default)
			)
			(layer "B.SilkS")
		)
		(fp_line
			(start 0.7874 -0.4064)
			(end -0.7874 -0.4064)
			(stroke
				(width 0.1524)
				(type default)
			)
			(layer "B.SilkS")
		)
		(fp_line
			(start -0.7874 0.4064)
			(end 0.7874 0.4064)
			(stroke
				(width 0.1524)
				(type default)
			)
			(layer "B.SilkS")
		)
		(fp_line
			(start -0.7874 -0.4064)
			(end -0.7874 0.4064)
			(stroke
				(width 0.1524)
				(type default)
			)
			(layer "B.SilkS")
		)
		(fp_line
			(start 0.67945 0.3048)
			(end 0.67945 -0.305054)
			(stroke
				(width 0.1)
				(type default)
			)
			(layer "B.Fab")
		)
		(fp_line
			(start 0.67945 -0.305054)
			(end 0.12065 -0.305054)
			(stroke
				(width 0.1)
				(type default)
			)
			(layer "B.Fab")
		)
		(fp_line
			(start 0.12065 0.3048)
			(end 0.67945 0.3048)
			(stroke
				(width 0.1)
				(type default)
			)
			(layer "B.Fab")
		)
		(fp_line
			(start 0.12065 0.2794)
			(end 0.12065 0.3048)
			(stroke
				(width 0.1)
				(type default)
			)
			(layer "B.Fab")
		)
		(fp_line
			(start 0.12065 -0.2794)
			(end -0.12065 -0.2794)
			(stroke
				(width 0.1)
				(type default)
			)
			(layer "B.Fab")
		)
		(fp_line
			(start 0.12065 -0.305054)
			(end 0.12065 -0.2794)
			(stroke
				(width 0.1)
				(type default)
			)
			(layer "B.Fab")
		)
		(fp_line
			(start -0.120396 0.3048)
			(end -0.120396 0.2794)
			(stroke
				(width 0.1)
				(type default)
			)
			(layer "B.Fab")
		)
		(fp_line
			(start -0.120396 0.2794)
			(end 0.12065 0.2794)
			(stroke
				(width 0.1)
				(type default)
			)
			(layer "B.Fab")
		)
		(fp_line
			(start -0.12065 -0.2794)
			(end -0.12065 -0.3048)
			(stroke
				(width 0.1)
				(type default)
			)
			(layer "B.Fab")
		)
		(fp_line
			(start -0.12065 -0.3048)
			(end -0.67945 -0.3048)
			(stroke
				(width 0.1)
				(type default)
			)
			(layer "B.Fab")
		)
		(fp_line
			(start -0.67945 0.3048)
			(end -0.120396 0.3048)
			(stroke
				(width 0.1)
				(type default)
			)
			(layer "B.Fab")
		)
		(fp_line
			(start -0.67945 -0.3048)
			(end -0.67945 0.3048)
			(stroke
				(width 0.1)
				(type default)
			)
			(layer "B.Fab")
		)
		(pad "1" smd circle
			(at 0.40005 0)
			(size 0 0)
			(layers "B.Cu" "B.Mask" "B.Paste")
			(net "LPC_ESPI_SEL_N")
		)
		(pad "2" smd circle
			(at -0.40005 0)
			(size 0 0)
			(layers "B.Cu" "B.Mask" "B.Paste")
			(net "GND")
		)
	)
	(footprint ""
		(layer "B.Cu")
		(at 57.242202 -66.0654 -90)
		(property "Reference" "R240"
			(at 0 0 90)
			(layer "B.SilkS")
			(hide yes)
			(effects
				(font
					(size 1.27 1.27)
				)
				(justify mirror)
			)
		)
		(property "Value" ""
			(at 0 0 90)
			(layer "B.Fab")
			(effects
				(font
					(size 1.27 1.27)
				)
				(justify mirror)
			)
		)
		(duplicate_pad_numbers_are_jumpers no)
		(fp_line
			(start -0.7874 0.4064)
			(end 0.7874 0.4064)
			(stroke
				(width 0.1524)
				(type default)
			)
			(layer "B.SilkS")
		)
		(fp_line
			(start 0.7874 0.4064)
			(end 0.7874 -0.4064)
			(stroke
				(width 0.1524)
				(type default)
			)
			(layer "B.SilkS")
		)
		(fp_line
			(start -0.7874 -0.4064)
			(end -0.7874 0.4064)
			(stroke
				(width 0.1524)
				(type default)
			)
			(layer "B.SilkS")
		)
		(fp_line
			(start 0.7874 -0.4064)
			(end -0.7874 -0.4064)
			(stroke
				(width 0.1524)
				(type default)
			)
			(layer "B.SilkS")
		)
		(fp_line
			(start -0.67945 0.3048)
			(end -0.120396 0.3048)
			(stroke
				(width 0.1)
				(type default)
			)
			(layer "B.Fab")
		)
		(fp_line
			(start -0.120396 0.3048)
			(end -0.120396 0.2794)
			(stroke
				(width 0.1)
				(type default)
			)
			(layer "B.Fab")
		)
		(fp_line
			(start 0.12065 0.3048)
			(end 0.67945 0.3048)
			(stroke
				(width 0.1)
				(type default)
			)
			(layer "B.Fab")
		)
		(fp_line
			(start 0.67945 0.3048)
			(end 0.67945 -0.305054)
			(stroke
				(width 0.1)
				(type default)
			)
			(layer "B.Fab")
		)
		(fp_line
			(start -0.120396 0.2794)
			(end 0.12065 0.2794)
			(stroke
				(width 0.1)
				(type default)
			)
			(layer "B.Fab")
		)
		(fp_line
			(start 0.12065 0.2794)
			(end 0.12065 0.3048)
			(stroke
				(width 0.1)
				(type default)
			)
			(layer "B.Fab")
		)
		(fp_line
			(start -0.12065 -0.2794)
			(end -0.12065 -0.3048)
			(stroke
				(width 0.1)
				(type default)
			)
			(layer "B.Fab")
		)
		(fp_line
			(start 0.12065 -0.2794)
			(end -0.12065 -0.2794)
			(stroke
				(width 0.1)
				(type default)
			)
			(layer "B.Fab")
		)
		(fp_line
			(start -0.67945 -0.3048)
			(end -0.67945 0.3048)
			(stroke
				(width 0.1)
				(type default)
			)
			(layer "B.Fab")
		)
		(fp_line
			(start -0.12065 -0.3048)
			(end -0.67945 -0.3048)
			(stroke
				(width 0.1)
				(type default)
			)
			(layer "B.Fab")
		)
		(fp_line
			(start 0.12065 -0.305054)
			(end 0.12065 -0.2794)
			(stroke
				(width 0.1)
				(type default)
			)
			(layer "B.Fab")
		)
		(fp_line
			(start 0.67945 -0.305054)
			(end 0.12065 -0.305054)
			(stroke
				(width 0.1)
				(type default)
			)
			(layer "B.Fab")
		)
		(pad "1" smd circle
			(at 0.40005 0 90)
			(size 0 0)
			(layers "B.Cu" "B.Mask" "B.Paste")
			(net "P3V3_AUX")
		)
		(pad "2" smd circle
			(at -0.40005 0 90)
			(size 0 0)
			(layers "B.Cu" "B.Mask" "B.Paste")
			(net "PU_FWSPIWP_N")
		)
	)
)
